# BASEBOARD_FAB2 (Tioga Pass) — schematic netlist excerpt (pin names and nets, part order shuffled) for the footprints in the layout excerpt that follows; sources: Cadence DE-HDL packaged netlist, KiCad conversion of Wiwynn_Tioga_Pass_MB.brd

R4F5  RES  1.00K 1% CHIP  pkg 0402  page 98 : A = M_A_VREF ; B = GND
C25W7  CAP_A  0.1UF 16V 10% X7R  pkg 0402V  page 147 : A = P3V3_STBY_BMC_ADCVREFP ; B = VCC_ADCAV3V3
C5A13  CAP_A  47UF 4V 20% X5R  pkg 0603V  page 220 : A = PVDDQ_DEF ; B = GND

(kicad_pcb
	(version 20260206)
	(generator "pcbnew")
	(generator_version "10.0")
	(general
		(thickness 1.6)
		(legacy_teardrops no)
	)
	(paper "A4")
	(title_block
		(title "Wiwynn_Tioga_Pass_MB.brd")
		(comment 1 "Tioga Pass / footprints 719-721 of 4770")
	)
	(layers
		(0 "F.Cu" signal "TOP")
		(4 "In1.Cu" signal "L2GND")
		(6 "In2.Cu" signal "L3")
		(8 "In3.Cu" signal "L4GND")
		(10 "In4.Cu" signal "L5")
		(12 "In5.Cu" signal "L6GND")
		(14 "In6.Cu" signal "L7VCC")
		(16 "In7.Cu" signal "L8VCC")
		(18 "In8.Cu" signal "L9GND")
		(20 "In9.Cu" signal "L10")
		(22 "In10.Cu" signal "L11GND")
		(24 "In11.Cu" signal "L12")
		(26 "In12.Cu" signal "L13GND")
		(2 "B.Cu" signal "BOTTOM")
		(9 "F.Adhes" user "F.Adhesive")
		(11 "B.Adhes" user "B.Adhesive")
		(13 "F.Paste" user "Package Geometry/Pastemask Top")
		(15 "B.Paste" user "Package Geometry/Pastemask Bottom")
		(5 "F.SilkS" user "Ref Des/Silkscreen Top")
		(7 "B.SilkS" user "Ref Des/Silkscreen Bottom")
		(1 "F.Mask" user "Board Geometry/Soldermask Top")
		(3 "B.Mask" user "Board Geometry/Soldermask Bottom")
		(17 "Dwgs.User" user "User.Drawings")
		(19 "Cmts.User" user "User.Comments")
		(21 "Eco1.User" user "User.Eco1")
		(23 "Eco2.User" user "User.Eco2")
		(25 "Edge.Cuts" user "Board Geometry/Outline")
		(27 "Margin" user)
		(31 "F.CrtYd" user "Package Geometry/Place Bound Top")
		(29 "B.CrtYd" user "Package Geometry/Place Bound Bottom")
		(35 "F.Fab" user "Ref Des/Assembly Top")
		(33 "B.Fab" user "Ref Des/Assembly Bottom")
	)
	(footprint ""
		(layer "F.Cu")
		(at 252.1585 -140.208 -90)
		(property "Reference" "C5A13"
			(at 1.848866 0.752348 270)
			(unlocked yes)
			(layer "F.SilkS")
			(effects
				(font
					(size 1.27 0.9652)
					(thickness 0.1524)
				)
			)
		)
		(property "Value" ""
			(at 0 0 270)
			(layer "F.Fab")
			(effects
				(font
					(size 1.27 1.27)
				)
			)
		)
		(duplicate_pad_numbers_are_jumpers no)
		(fp_rect
			(start -0.500126 1.598422)
			(end 0.500126 -0.201422)
			(stroke
				(width 0)
				(type default)
			)
			(fill no)
			(layer "F.CrtYd")
		)
		(fp_line
			(start -0.500126 1.598422)
			(end -0.500126 -0.201422)
			(stroke
				(width 0.1)
				(type default)
			)
			(layer "F.Fab")
		)
		(fp_line
			(start 0.500126 1.598422)
			(end -0.500126 1.598422)
			(stroke
				(width 0.1)
				(type default)
			)
			(layer "F.Fab")
		)
		(fp_line
			(start -0.500126 -0.201422)
			(end 0.500126 -0.201422)
			(stroke
				(width 0.1)
				(type default)
			)
			(layer "F.Fab")
		)
		(fp_line
			(start 0.500126 -0.201422)
			(end 0.500126 1.598422)
			(stroke
				(width 0.1)
				(type default)
			)
			(layer "F.Fab")
		)
		(pad "1" smd rect
			(at 0 0 180)
			(size 0.889 0.9906)
			(layers "F.Cu" "F.Mask" "F.Paste")
			(net "PVDDQ_DEF")
		)
		(pad "2" smd rect
			(at 0 1.397 180)
			(size 0.889 0.9906)
			(layers "F.Cu" "F.Mask" "F.Paste")
			(net "GND")
		)
		(zone
			(layer "F.Cu")
			(hatch none 0.5)
			(connect_pads
				(clearance 0)
			)
			(min_thickness 0.25)
			(keepout
				(tracks not_allowed)
				(vias allowed)
				(pads allowed)
				(copperpour not_allowed)
				(footprints allowed)
			)
			(placement
				(enabled no)
				(sheetname "")
			)
			(fill
				(thermal_gap 0.5)
				(thermal_bridge_width 0.5)
				(island_removal_mode 0)
			)
			(polygon
				(pts
					(xy 251.206 -140.7033) (xy 251.206 -139.7127) (xy 251.714 -139.7127) (xy 251.714 -140.7033)
				)
			)
		)
		(zone
			(layer "F.Cu")
			(hatch none 0.5)
			(connect_pads
				(clearance 0)
			)
			(min_thickness 0.25)
			(keepout
				(tracks allowed)
				(vias not_allowed)
				(pads allowed)
				(copperpour not_allowed)
				(footprints allowed)
			)
			(placement
				(enabled no)
				(sheetname "")
			)
			(fill
				(thermal_gap 0.5)
				(thermal_bridge_width 0.5)
				(island_removal_mode 0)
			)
			(polygon
				(pts
					(xy 251.206 -140.7033) (xy 251.206 -139.7127) (xy 251.714 -139.7127) (xy 251.714 -140.7033)
				)
			)
		)
	)
	(footprint ""
		(layer "F.Cu")
		(at 194.564 -22.507194 180)
		(property "Reference" "R4F5"
			(at 0 0 180)
			(layer "F.SilkS")
			(hide yes)
			(effects
				(font
					(size 1.27 1.27)
				)
			)
		)
		(property "Value" ""
			(at 0 0 180)
			(layer "F.Fab")
			(effects
				(font
					(size 1.27 1.27)
				)
			)
		)
		(duplicate_pad_numbers_are_jumpers no)
		(fp_poly
			(pts
				(xy -0.2794 -0.1016) (xy 0.2794 -0.1016) (xy 0.2794 0.9906) (xy -0.2794 0.9906)
			)
			(stroke
				(width 0)
				(type default)
			)
			(fill no)
			(layer "F.CrtYd")
		)
		(fp_line
			(start 0.2794 0.9906)
			(end 0.2794 -0.1016)
			(stroke
				(width 0.1)
				(type default)
			)
			(layer "F.Fab")
		)
		(fp_line
			(start 0.2794 -0.1016)
			(end -0.2794 -0.1016)
			(stroke
				(width 0.1)
				(type default)
			)
			(layer "F.Fab")
		)
		(fp_line
			(start -0.2794 0.9906)
			(end 0.2794 0.9906)
			(stroke
				(width 0.1)
				(type default)
			)
			(layer "F.Fab")
		)
		(fp_line
			(start -0.2794 -0.1016)
			(end -0.2794 0.9906)
			(stroke
				(width 0.1)
				(type default)
			)
			(layer "F.Fab")
		)
		(pad "1" smd rect
			(at 0 0 180)
			(size 0.508 0.508)
			(layers "F.Cu" "F.Mask" "F.Paste")
			(net "M_A_VREF")
		)
		(pad "2" smd rect
			(at 0 0.889 180)
			(size 0.508 0.508)
			(layers "F.Cu" "F.Mask" "F.Paste")
			(net "GND")
		)
		(zone
			(layer "F.Cu")
			(hatch none 0.5)
			(connect_pads
				(clearance 0)
			)
			(min_thickness 0.25)
			(keepout
				(tracks not_allowed)
				(vias allowed)
				(pads allowed)
				(copperpour not_allowed)
				(footprints allowed)
			)
			(placement
				(enabled no)
				(sheetname "")
			)
			(fill
				(thermal_gap 0.5)
				(thermal_bridge_width 0.5)
				(island_removal_mode 0)
			)
			(polygon
				(pts
					(xy 194.818 -23.142194) (xy 194.31 -23.142194) (xy 194.31 -22.761194) (xy 194.818 -22.761194)
				)
			)
		)
		(zone
			(layer "F.Cu")
			(hatch none 0.5)
			(connect_pads
				(clearance 0)
			)
			(min_thickness 0.25)
			(keepout
				(tracks allowed)
				(vias not_allowed)
				(pads allowed)
				(copperpour not_allowed)
				(footprints allowed)
			)
			(placement
				(enabled no)
				(sheetname "")
			)
			(fill
				(thermal_gap 0.5)
				(thermal_bridge_width 0.5)
				(island_removal_mode 0)
			)
			(polygon
				(pts
					(xy 194.818 -22.761194) (xy 194.31 -22.761194) (xy 194.31 -23.142194) (xy 194.818 -23.142194)
				)
			)
		)
	)
	(footprint ""
		(layer "F.Cu")
		(at 411.086046 -22.196552)
		(property "Reference" "C25W7"
			(at -0.8382 -0.67818 0)
			(unlocked yes)
			(layer "F.SilkS")
			(effects
				(font
					(size 0.4064 0.254)
					(thickness 0.1524)
				)
				(justify left)
			)
		)
		(property "Value" ""
			(at 0 0 0)
			(layer "F.Fab")
			(effects
				(font
					(size 1.27 1.27)
				)
			)
		)
		(duplicate_pad_numbers_are_jumpers no)
		(fp_poly
			(pts
				(xy 0.3048 -0.1016) (xy 0.3048 0.9906) (xy -0.3048 0.9906) (xy -0.3048 -0.1016)
			)
			(stroke
				(width 0)
				(type default)
			)
			(fill no)
			(layer "F.CrtYd")
		)
		(fp_line
			(start -0.3048 -0.1016)
			(end -0.3048 0.9906)
			(stroke
				(width 0.1)
				(type default)
			)
			(layer "F.Fab")
		)
		(fp_line
			(start -0.3048 0.9906)
			(end 0.3048 0.9906)
			(stroke
				(width 0.1)
				(type default)
			)
			(layer "F.Fab")
		)
		(fp_line
			(start 0.3048 -0.1016)
			(end -0.3048 -0.1016)
			(stroke
				(width 0.1)
				(type default)
			)
			(layer "F.Fab")
		)
		(fp_line
			(start 0.3048 0.9906)
			(end 0.3048 -0.1016)
			(stroke
				(width 0.1)
				(type default)
			)
			(layer "F.Fab")
		)
		(pad "1" smd rect
			(at 0 0)
			(size 0.508 0.508)
			(layers "F.Cu" "F.Mask" "F.Paste")
			(net "P3V3_STBY_BMC_ADCVREFP")
		)
		(pad "2" smd rect
			(at 0 0.889)
			(size 0.508 0.508)
			(layers "F.Cu" "F.Mask" "F.Paste")
			(net "VCC_ADCAV3V3")
		)
		(zone
			(layer "F.Cu")
			(hatch none 0.5)
			(connect_pads
				(clearance 0)
			)
			(min_thickness 0.25)
			(keepout
				(tracks allowed)
				(vias not_allowed)
				(pads allowed)
				(copperpour not_allowed)
				(footprints allowed)
			)
			(placement
				(enabled no)
				(sheetname "")
			)
			(fill
				(thermal_gap 0.5)
				(thermal_bridge_width 0.5)
				(island_removal_mode 0)
			)
			(polygon
				(pts
					(xy 410.832046 -21.942552) (xy 411.340046 -21.942552) (xy 411.340046 -21.561552) (xy 410.832046 -21.561552)
				)
			)
		)
		(zone
			(layer "F.Cu")
			(hatch none 0.5)
			(connect_pads
				(clearance 0)
			)
			(min_thickness 0.25)
			(keepout
				(tracks not_allowed)
				(vias allowed)
				(pads allowed)
				(copperpour not_allowed)
				(footprints allowed)
			)
			(placement
				(enabled no)
				(sheetname "")
			)
			(fill
				(thermal_gap 0.5)
				(thermal_bridge_width 0.5)
				(island_removal_mode 0)
			)
			(polygon
				(pts
					(xy 410.832046 -21.561552) (xy 411.340046 -21.561552) (xy 411.340046 -21.942552) (xy 410.832046 -21.942552)
				)
			)
		)
	)
)
